(kicad_pcb
	(version 20260206)
	(generator "pcbnew")
	(generator_version "10.0")
	(general
		(thickness 1.6)
		(legacy_teardrops no)
	)
	(paper "A4")
	(title_block
		(title "03242023_DA0F0TMBIJ0_F0T_Motherboard_J_brd_V01_OCP.brd")
		(comment 1 "Grand Teton / footprints 3492-3497 of 6105")
	)
	(layers
		(0 "F.Cu" signal "TOP")
		(4 "In1.Cu" signal "GND")
		(6 "In2.Cu" signal "IN1")
		(8 "In3.Cu" signal "GND1")
		(10 "In4.Cu" signal "IN2")
		(12 "In5.Cu" signal "GND2")
		(14 "In6.Cu" signal "IN3")
		(16 "In7.Cu" signal "GND3")
		(18 "In8.Cu" signal "VCC")
		(20 "In9.Cu" signal "VCC1")
		(22 "In10.Cu" signal "GND4")
		(24 "In11.Cu" signal "IN4")
		(26 "In12.Cu" signal "GND5")
		(28 "In13.Cu" signal "IN5")
		(30 "In14.Cu" signal "GND6")
		(32 "In15.Cu" signal "IN6")
		(34 "In16.Cu" signal "GND7")
		(2 "B.Cu" signal "BOTTOM")
		(9 "F.Adhes" user "F.Adhesive")
		(11 "B.Adhes" user "B.Adhesive")
		(13 "F.Paste" user "Package Geometry/Pastemask Top")
		(15 "B.Paste" user "Package Geometry/Pastemask Bottom")
		(5 "F.SilkS" user "Ref Des/Silkscreen Top")
		(7 "B.SilkS" user "Ref Des/Silkscreen Bottom")
		(1 "F.Mask" user "Board Geometry/Soldermask Top")
		(3 "B.Mask" user "Board Geometry/Soldermask Bottom")
		(17 "Dwgs.User" user "User.Drawings")
		(19 "Cmts.User" user "User.Comments")
		(21 "Eco1.User" user "User.Eco1")
		(23 "Eco2.User" user "User.Eco2")
		(25 "Edge.Cuts" user "Board Geometry/Outline")
		(27 "Margin" user)
		(31 "F.CrtYd" user "Package Geometry/Place Bound Top")
		(29 "B.CrtYd" user "Package Geometry/Place Bound Bottom")
		(35 "F.Fab" user "Ref Des/Assembly Top")
		(33 "B.Fab" user "Ref Des/Assembly Bottom")
	)
	(footprint ""
		(layer "F.Cu")
		(at 118.671594 -93.404182 -90)
		(property "Reference" "C2243"
			(at 0 0 270)
			(layer "F.SilkS")
			(hide yes)
			(effects
				(font
					(size 1.27 1.27)
				)
			)
		)
		(property "Value" ""
			(at 0 0 270)
			(layer "F.Fab")
			(effects
				(font
					(size 1.27 1.27)
				)
			)
		)
		(duplicate_pad_numbers_are_jumpers no)
		(fp_line
			(start -0.7874 0.4064)
			(end -0.7874 -0.4064)
			(stroke
				(width 0.1524)
				(type default)
			)
			(layer "F.SilkS")
		)
		(fp_line
			(start 0.7874 0.4064)
			(end -0.7874 0.4064)
			(stroke
				(width 0.1524)
				(type default)
			)
			(layer "F.SilkS")
		)
		(fp_line
			(start -0.7874 -0.4064)
			(end 0.7874 -0.4064)
			(stroke
				(width 0.1524)
				(type default)
			)
			(layer "F.SilkS")
		)
		(fp_line
			(start 0.7874 -0.4064)
			(end 0.7874 0.4064)
			(stroke
				(width 0.1524)
				(type default)
			)
			(layer "F.SilkS")
		)
		(fp_line
			(start -0.67945 0.3048)
			(end -0.67945 -0.305054)
			(stroke
				(width 0.1)
				(type default)
			)
			(layer "F.Fab")
		)
		(fp_line
			(start -0.12065 0.3048)
			(end -0.67945 0.3048)
			(stroke
				(width 0.1)
				(type default)
			)
			(layer "F.Fab")
		)
		(fp_line
			(start 0.120396 0.3048)
			(end 0.120396 0.2794)
			(stroke
				(width 0.1)
				(type default)
			)
			(layer "F.Fab")
		)
		(fp_line
			(start 0.67945 0.3048)
			(end 0.120396 0.3048)
			(stroke
				(width 0.1)
				(type default)
			)
			(layer "F.Fab")
		)
		(fp_line
			(start -0.12065 0.2794)
			(end -0.12065 0.3048)
			(stroke
				(width 0.1)
				(type default)
			)
			(layer "F.Fab")
		)
		(fp_line
			(start 0.120396 0.2794)
			(end -0.12065 0.2794)
			(stroke
				(width 0.1)
				(type default)
			)
			(layer "F.Fab")
		)
		(fp_line
			(start -0.12065 -0.2794)
			(end 0.12065 -0.2794)
			(stroke
				(width 0.1)
				(type default)
			)
			(layer "F.Fab")
		)
		(fp_line
			(start 0.12065 -0.2794)
			(end 0.12065 -0.3048)
			(stroke
				(width 0.1)
				(type default)
			)
			(layer "F.Fab")
		)
		(fp_line
			(start 0.12065 -0.3048)
			(end 0.67945 -0.3048)
			(stroke
				(width 0.1)
				(type default)
			)
			(layer "F.Fab")
		)
		(fp_line
			(start 0.67945 -0.3048)
			(end 0.67945 0.3048)
			(stroke
				(width 0.1)
				(type default)
			)
			(layer "F.Fab")
		)
		(fp_line
			(start -0.67945 -0.305054)
			(end -0.12065 -0.305054)
			(stroke
				(width 0.1)
				(type default)
			)
			(layer "F.Fab")
		)
		(fp_line
			(start -0.12065 -0.305054)
			(end -0.12065 -0.2794)
			(stroke
				(width 0.1)
				(type default)
			)
			(layer "F.Fab")
		)
		(pad "1" smd circle
			(at -0.40005 0 270)
			(size 0 0)
			(layers "F.Cu" "F.Mask" "F.Paste")
			(net "P3V3")
		)
		(pad "2" smd circle
			(at 0.40005 0 270)
			(size 0 0)
			(layers "F.Cu" "F.Mask" "F.Paste")
			(net "GND")
		)
	)
	(footprint ""
		(layer "F.Cu")
		(at 145.34388 -56.225948 180)
		(property "Reference" "R2410"
			(at 0 0 180)
			(layer "F.SilkS")
			(hide yes)
			(effects
				(font
					(size 1.27 1.27)
				)
			)
		)
		(property "Value" ""
			(at 0 0 180)
			(layer "F.Fab")
			(effects
				(font
					(size 1.27 1.27)
				)
			)
		)
		(duplicate_pad_numbers_are_jumpers no)
		(fp_line
			(start 0.7874 0.4064)
			(end -0.7874 0.4064)
			(stroke
				(width 0.1524)
				(type default)
			)
			(layer "F.SilkS")
		)
		(fp_line
			(start 0.7874 -0.4064)
			(end 0.7874 0.4064)
			(stroke
				(width 0.1524)
				(type default)
			)
			(layer "F.SilkS")
		)
		(fp_line
			(start -0.7874 0.4064)
			(end -0.7874 -0.4064)
			(stroke
				(width 0.1524)
				(type default)
			)
			(layer "F.SilkS")
		)
		(fp_line
			(start -0.7874 -0.4064)
			(end 0.7874 -0.4064)
			(stroke
				(width 0.1524)
				(type default)
			)
			(layer "F.SilkS")
		)
		(fp_line
			(start 0.67945 0.3048)
			(end 0.120396 0.3048)
			(stroke
				(width 0.1)
				(type default)
			)
			(layer "F.Fab")
		)
		(fp_line
			(start 0.67945 -0.3048)
			(end 0.67945 0.3048)
			(stroke
				(width 0.1)
				(type default)
			)
			(layer "F.Fab")
		)
		(fp_line
			(start 0.12065 -0.2794)
			(end 0.12065 -0.3048)
			(stroke
				(width 0.1)
				(type default)
			)
			(layer "F.Fab")
		)
		(fp_line
			(start 0.12065 -0.3048)
			(end 0.67945 -0.3048)
			(stroke
				(width 0.1)
				(type default)
			)
			(layer "F.Fab")
		)
		(fp_line
			(start 0.120396 0.3048)
			(end 0.120396 0.2794)
			(stroke
				(width 0.1)
				(type default)
			)
			(layer "F.Fab")
		)
		(fp_line
			(start 0.120396 0.2794)
			(end -0.12065 0.2794)
			(stroke
				(width 0.1)
				(type default)
			)
			(layer "F.Fab")
		)
		(fp_line
			(start -0.12065 0.3048)
			(end -0.67945 0.3048)
			(stroke
				(width 0.1)
				(type default)
			)
			(layer "F.Fab")
		)
		(fp_line
			(start -0.12065 0.2794)
			(end -0.12065 0.3048)
			(stroke
				(width 0.1)
				(type default)
			)
			(layer "F.Fab")
		)
		(fp_line
			(start -0.12065 -0.2794)
			(end 0.12065 -0.2794)
			(stroke
				(width 0.1)
				(type default)
			)
			(layer "F.Fab")
		)
		(fp_line
			(start -0.12065 -0.305054)
			(end -0.12065 -0.2794)
			(stroke
				(width 0.1)
				(type default)
			)
			(layer "F.Fab")
		)
		(fp_line
			(start -0.67945 0.3048)
			(end -0.67945 -0.305054)
			(stroke
				(width 0.1)
				(type default)
			)
			(layer "F.Fab")
		)
		(fp_line
			(start -0.67945 -0.305054)
			(end -0.12065 -0.305054)
			(stroke
				(width 0.1)
				(type default)
			)
			(layer "F.Fab")
		)
		(pad "1" smd circle
			(at -0.40005 0 180)
			(size 0 0)
			(layers "F.Cu" "F.Mask" "F.Paste")
			(net "SMB_M2_P0_1V8AUX_SDA_R")
		)
		(pad "2" smd circle
			(at 0.40005 0 180)
			(size 0 0)
			(layers "F.Cu" "F.Mask" "F.Paste")
			(net "SMB_M2_P0_1V8AUX_SDA")
		)
	)
	(footprint ""
		(layer "F.Cu")
		(at 239.949736 -39.424864)
		(property "Reference" "H76"
			(at -0.155702 -3.208274 0)
			(unlocked yes)
			(layer "B.SilkS")
			(effects
				(font
					(size 0.7874 0.5842)
					(thickness 0.1524)
				)
				(justify left mirror)
			)
		)
		(property "Value" ""
			(at 0 0 0)
			(layer "F.Fab")
			(effects
				(font
					(size 1.27 1.27)
				)
			)
		)
		(duplicate_pad_numbers_are_jumpers no)
		(pad "1" thru_hole rect
			(at 0 0)
			(size 4.2164 5.0038)
			(drill 2.0066
				(offset 0.099822 0)
			)
			(layers "*.Cu" "*.Mask")
			(remove_unused_layers no)
			(net "GND")
			(clearance -0.8509)
			(padstack
				(mode front_inner_back)
				(layer "Inner"
					(shape circle)
					(size 4.0132 4.0132)
					(clearance -0.7493)
				)
				(layer "B.Cu"
					(shape circle)
					(size 4.0132 4.0132)
					(clearance -0.7493)
				)
			)
		)
	)
	(footprint ""
		(layer "F.Cu")
		(at 352.217736 -338.86013)
		(property "Reference" "PR150"
			(at 0 0 0)
			(layer "F.SilkS")
			(hide yes)
			(effects
				(font
					(size 1.27 1.27)
				)
			)
		)
		(property "Value" ""
			(at 0 0 0)
			(layer "F.Fab")
			(effects
				(font
					(size 1.27 1.27)
				)
			)
		)
		(duplicate_pad_numbers_are_jumpers no)
		(fp_line
			(start -0.7874 -0.4064)
			(end 0.7874 -0.4064)
			(stroke
				(width 0.1524)
				(type default)
			)
			(layer "F.SilkS")
		)
		(fp_line
			(start -0.7874 0.4064)
			(end -0.7874 -0.4064)
			(stroke
				(width 0.1524)
				(type default)
			)
			(layer "F.SilkS")
		)
		(fp_line
			(start 0.7874 -0.4064)
			(end 0.7874 0.4064)
			(stroke
				(width 0.1524)
				(type default)
			)
			(layer "F.SilkS")
		)
		(fp_line
			(start 0.7874 0.4064)
			(end -0.7874 0.4064)
			(stroke
				(width 0.1524)
				(type default)
			)
			(layer "F.SilkS")
		)
		(fp_line
			(start -0.67945 -0.305054)
			(end -0.12065 -0.305054)
			(stroke
				(width 0.1)
				(type default)
			)
			(layer "F.Fab")
		)
		(fp_line
			(start -0.67945 0.3048)
			(end -0.67945 -0.305054)
			(stroke
				(width 0.1)
				(type default)
			)
			(layer "F.Fab")
		)
		(fp_line
			(start -0.12065 -0.305054)
			(end -0.12065 -0.2794)
			(stroke
				(width 0.1)
				(type default)
			)
			(layer "F.Fab")
		)
		(fp_line
			(start -0.12065 -0.2794)
			(end 0.12065 -0.2794)
			(stroke
				(width 0.1)
				(type default)
			)
			(layer "F.Fab")
		)
		(fp_line
			(start -0.12065 0.2794)
			(end -0.12065 0.3048)
			(stroke
				(width 0.1)
				(type default)
			)
			(layer "F.Fab")
		)
		(fp_line
			(start -0.12065 0.3048)
			(end -0.67945 0.3048)
			(stroke
				(width 0.1)
				(type default)
			)
			(layer "F.Fab")
		)
		(fp_line
			(start 0.120396 0.2794)
			(end -0.12065 0.2794)
			(stroke
				(width 0.1)
				(type default)
			)
			(layer "F.Fab")
		)
		(fp_line
			(start 0.120396 0.3048)
			(end 0.120396 0.2794)
			(stroke
				(width 0.1)
				(type default)
			)
			(layer "F.Fab")
		)
		(fp_line
			(start 0.12065 -0.3048)
			(end 0.67945 -0.3048)
			(stroke
				(width 0.1)
				(type default)
			)
			(layer "F.Fab")
		)
		(fp_line
			(start 0.12065 -0.2794)
			(end 0.12065 -0.3048)
			(stroke
				(width 0.1)
				(type default)
			)
			(layer "F.Fab")
		)
		(fp_line
			(start 0.67945 -0.3048)
			(end 0.67945 0.3048)
			(stroke
				(width 0.1)
				(type default)
			)
			(layer "F.Fab")
		)
		(fp_line
			(start 0.67945 0.3048)
			(end 0.120396 0.3048)
			(stroke
				(width 0.1)
				(type default)
			)
			(layer "F.Fab")
		)
		(pad "1" smd circle
			(at -0.40005 0)
			(size 0 0)
			(layers "F.Cu" "F.Mask" "F.Paste")
			(net "PVCCIN_CPU0_LSET2")
		)
		(pad "2" smd circle
			(at 0.40005 0)
			(size 0 0)
			(layers "F.Cu" "F.Mask" "F.Paste")
			(net "GND")
		)
	)
	(footprint ""
		(layer "F.Cu")
		(at 61.543438 -31.887922 90)
		(property "Reference" "R3874"
			(at 0 0 90)
			(layer "F.SilkS")
			(hide yes)
			(effects
				(font
					(size 1.27 1.27)
				)
			)
		)
		(property "Value" ""
			(at 0 0 90)
			(layer "F.Fab")
			(effects
				(font
					(size 1.27 1.27)
				)
			)
		)
		(duplicate_pad_numbers_are_jumpers no)
		(fp_line
			(start 0.7874 -0.4064)
			(end 0.7874 0.4064)
			(stroke
				(width 0.1524)
				(type default)
			)
			(layer "F.SilkS")
		)
		(fp_line
			(start -0.7874 -0.4064)
			(end 0.7874 -0.4064)
			(stroke
				(width 0.1524)
				(type default)
			)
			(layer "F.SilkS")
		)
		(fp_line
			(start 0.7874 0.4064)
			(end -0.7874 0.4064)
			(stroke
				(width 0.1524)
				(type default)
			)
			(layer "F.SilkS")
		)
		(fp_line
			(start -0.7874 0.4064)
			(end -0.7874 -0.4064)
			(stroke
				(width 0.1524)
				(type default)
			)
			(layer "F.SilkS")
		)
		(fp_line
			(start -0.12065 -0.305054)
			(end -0.12065 -0.2794)
			(stroke
				(width 0.1)
				(type default)
			)
			(layer "F.Fab")
		)
		(fp_line
			(start -0.67945 -0.305054)
			(end -0.12065 -0.305054)
			(stroke
				(width 0.1)
				(type default)
			)
			(layer "F.Fab")
		)
		(fp_line
			(start 0.67945 -0.3048)
			(end 0.67945 0.3048)
			(stroke
				(width 0.1)
				(type default)
			)
			(layer "F.Fab")
		)
		(fp_line
			(start 0.12065 -0.3048)
			(end 0.67945 -0.3048)
			(stroke
				(width 0.1)
				(type default)
			)
			(layer "F.Fab")
		)
		(fp_line
			(start 0.12065 -0.2794)
			(end 0.12065 -0.3048)
			(stroke
				(width 0.1)
				(type default)
			)
			(layer "F.Fab")
		)
		(fp_line
			(start -0.12065 -0.2794)
			(end 0.12065 -0.2794)
			(stroke
				(width 0.1)
				(type default)
			)
			(layer "F.Fab")
		)
		(fp_line
			(start 0.120396 0.2794)
			(end -0.12065 0.2794)
			(stroke
				(width 0.1)
				(type default)
			)
			(layer "F.Fab")
		)
		(fp_line
			(start -0.12065 0.2794)
			(end -0.12065 0.3048)
			(stroke
				(width 0.1)
				(type default)
			)
			(layer "F.Fab")
		)
		(fp_line
			(start 0.67945 0.3048)
			(end 0.120396 0.3048)
			(stroke
				(width 0.1)
				(type default)
			)
			(layer "F.Fab")
		)
		(fp_line
			(start 0.120396 0.3048)
			(end 0.120396 0.2794)
			(stroke
				(width 0.1)
				(type default)
			)
			(layer "F.Fab")
		)
		(fp_line
			(start -0.12065 0.3048)
			(end -0.67945 0.3048)
			(stroke
				(width 0.1)
				(type default)
			)
			(layer "F.Fab")
		)
		(fp_line
			(start -0.67945 0.3048)
			(end -0.67945 -0.305054)
			(stroke
				(width 0.1)
				(type default)
			)
			(layer "F.Fab")
		)
		(pad "1" smd circle
			(at -0.40005 0 90)
			(size 0 0)
			(layers "F.Cu" "F.Mask" "F.Paste")
			(net "P12V_OCP_IMON_2")
		)
		(pad "2" smd circle
			(at 0.40005 0 90)
			(size 0 0)
			(layers "F.Cu" "F.Mask" "F.Paste")
			(net "P12V_OCP_V3_2_ISENSE_MPS_TIC")
		)
	)
	(footprint ""
		(layer "F.Cu")
		(at 201.00036 -116.804948 180)
		(property "Reference" "R4157"
			(at 0 0 180)
			(layer "F.SilkS")
			(hide yes)
			(effects
				(font
					(size 1.27 1.27)
				)
			)
		)
		(property "Value" ""
			(at 0 0 180)
			(layer "F.Fab")
			(effects
				(font
					(size 1.27 1.27)
				)
			)
		)
		(duplicate_pad_numbers_are_jumpers no)
		(fp_line
			(start 0.7874 0.4064)
			(end -0.7874 0.4064)
			(stroke
				(width 0.1524)
				(type default)
			)
			(layer "F.SilkS")
		)
		(fp_line
			(start 0.7874 -0.4064)
			(end 0.7874 0.4064)
			(stroke
				(width 0.1524)
				(type default)
			)
			(layer "F.SilkS")
		)
		(fp_line
			(start -0.7874 0.4064)
			(end -0.7874 -0.4064)
			(stroke
				(width 0.1524)
				(type default)
			)
			(layer "F.SilkS")
		)
		(fp_line
			(start -0.7874 -0.4064)
			(end 0.7874 -0.4064)
			(stroke
				(width 0.1524)
				(type default)
			)
			(layer "F.SilkS")
		)
		(fp_line
			(start 0.67945 0.3048)
			(end 0.120396 0.3048)
			(stroke
				(width 0.1)
				(type default)
			)
			(layer "F.Fab")
		)
		(fp_line
			(start 0.67945 -0.3048)
			(end 0.67945 0.3048)
			(stroke
				(width 0.1)
				(type default)
			)
			(layer "F.Fab")
		)
		(fp_line
			(start 0.12065 -0.2794)
			(end 0.12065 -0.3048)
			(stroke
				(width 0.1)
				(type default)
			)
			(layer "F.Fab")
		)
		(fp_line
			(start 0.12065 -0.3048)
			(end 0.67945 -0.3048)
			(stroke
				(width 0.1)
				(type default)
			)
			(layer "F.Fab")
		)
		(fp_line
			(start 0.120396 0.3048)
			(end 0.120396 0.2794)
			(stroke
				(width 0.1)
				(type default)
			)
			(layer "F.Fab")
		)
		(fp_line
			(start 0.120396 0.2794)
			(end -0.12065 0.2794)
			(stroke
				(width 0.1)
				(type default)
			)
			(layer "F.Fab")
		)
		(fp_line
			(start -0.12065 0.3048)
			(end -0.67945 0.3048)
			(stroke
				(width 0.1)
				(type default)
			)
			(layer "F.Fab")
		)
		(fp_line
			(start -0.12065 0.2794)
			(end -0.12065 0.3048)
			(stroke
				(width 0.1)
				(type default)
			)
			(layer "F.Fab")
		)
		(fp_line
			(start -0.12065 -0.2794)
			(end 0.12065 -0.2794)
			(stroke
				(width 0.1)
				(type default)
			)
			(layer "F.Fab")
		)
		(fp_line
			(start -0.12065 -0.305054)
			(end -0.12065 -0.2794)
			(stroke
				(width 0.1)
				(type default)
			)
			(layer "F.Fab")
		)
		(fp_line
			(start -0.67945 0.3048)
			(end -0.67945 -0.305054)
			(stroke
				(width 0.1)
				(type default)
			)
			(layer "F.Fab")
		)
		(fp_line
			(start -0.67945 -0.305054)
			(end -0.12065 -0.305054)
			(stroke
				(width 0.1)
				(type default)
			)
			(layer "F.Fab")
		)
		(pad "1" smd circle
			(at -0.40005 0 180)
			(size 0 0)
			(layers "F.Cu" "F.Mask" "F.Paste")
			(net "PRSNT_CABLE_GPU_A1_ISO_N")
		)
		(pad "2" smd circle
			(at 0.40005 0 180)
			(size 0 0)
			(layers "F.Cu" "F.Mask" "F.Paste")
			(net "PRSNT_CABLE_GPU_A1_ISO_R_N")
		)
	)
)
